(kicad_pcb
	(version 20260206)
	(generator "pcbnew")
	(generator_version "10.0")
	(general
		(thickness 1.6)
		(legacy_teardrops no)
	)
	(paper "A4")
	(title_block
		(title "01162023_DA0F0TEBIF0_F0T_Expander_BD_F_brd_V02_OCP.brd")
		(comment 1 "Grand Teton / footprints 6501-6506 of 9728")
	)
	(layers
		(0 "F.Cu" signal "TOP")
		(4 "In1.Cu" signal "GND")
		(6 "In2.Cu" signal "VCC")
		(8 "In3.Cu" signal "VCC1")
		(10 "In4.Cu" signal "GND1")
		(12 "In5.Cu" signal "IN1")
		(14 "In6.Cu" signal "GND2")
		(16 "In7.Cu" signal "IN2")
		(18 "In8.Cu" signal "GND3")
		(20 "In9.Cu" signal "IN3")
		(22 "In10.Cu" signal "GND4")
		(24 "In11.Cu" signal "IN4")
		(26 "In12.Cu" signal "GND5")
		(28 "In13.Cu" signal "IN5")
		(30 "In14.Cu" signal "GND6")
		(32 "In15.Cu" signal "IN6")
		(34 "In16.Cu" signal "GND7")
		(2 "B.Cu" signal "BOTTOM")
		(9 "F.Adhes" user "F.Adhesive")
		(11 "B.Adhes" user "B.Adhesive")
		(13 "F.Paste" user "Package Geometry/Pastemask Top")
		(15 "B.Paste" user "Package Geometry/Pastemask Bottom")
		(5 "F.SilkS" user "Ref Des/Silkscreen Top")
		(7 "B.SilkS" user "Ref Des/Silkscreen Bottom")
		(1 "F.Mask" user "Board Geometry/Soldermask Top")
		(3 "B.Mask" user "Board Geometry/Soldermask Bottom")
		(17 "Dwgs.User" user "User.Drawings")
		(19 "Cmts.User" user "User.Comments")
		(21 "Eco1.User" user "User.Eco1")
		(23 "Eco2.User" user "User.Eco2")
		(25 "Edge.Cuts" user "Board Geometry/Outline")
		(27 "Margin" user)
		(31 "F.CrtYd" user "Package Geometry/Place Bound Top")
		(29 "B.CrtYd" user "Package Geometry/Place Bound Bottom")
		(35 "F.Fab" user "Ref Des/Assembly Top")
		(33 "B.Fab" user "Ref Des/Assembly Bottom")
	)
	(footprint ""
		(layer "F.Cu")
		(at 291.194998 -102.798372 180)
		(property "Reference" "R274"
			(at 0 0 180)
			(layer "F.SilkS")
			(hide yes)
			(effects
				(font
					(size 1.27 1.27)
				)
			)
		)
		(property "Value" ""
			(at 0 0 180)
			(layer "F.Fab")
			(effects
				(font
					(size 1.27 1.27)
				)
			)
		)
		(duplicate_pad_numbers_are_jumpers no)
		(fp_line
			(start 0.7874 0.4064)
			(end -0.7874 0.4064)
			(stroke
				(width 0.1524)
				(type default)
			)
			(layer "F.SilkS")
		)
		(fp_line
			(start 0.7874 -0.4064)
			(end 0.7874 0.4064)
			(stroke
				(width 0.1524)
				(type default)
			)
			(layer "F.SilkS")
		)
		(fp_line
			(start -0.7874 0.4064)
			(end -0.7874 -0.4064)
			(stroke
				(width 0.1524)
				(type default)
			)
			(layer "F.SilkS")
		)
		(fp_line
			(start -0.7874 -0.4064)
			(end 0.7874 -0.4064)
			(stroke
				(width 0.1524)
				(type default)
			)
			(layer "F.SilkS")
		)
		(fp_line
			(start 0.67945 0.3048)
			(end 0.120396 0.3048)
			(stroke
				(width 0.1)
				(type default)
			)
			(layer "F.Fab")
		)
		(fp_line
			(start 0.67945 -0.3048)
			(end 0.67945 0.3048)
			(stroke
				(width 0.1)
				(type default)
			)
			(layer "F.Fab")
		)
		(fp_line
			(start 0.12065 -0.2794)
			(end 0.12065 -0.3048)
			(stroke
				(width 0.1)
				(type default)
			)
			(layer "F.Fab")
		)
		(fp_line
			(start 0.12065 -0.3048)
			(end 0.67945 -0.3048)
			(stroke
				(width 0.1)
				(type default)
			)
			(layer "F.Fab")
		)
		(fp_line
			(start 0.120396 0.3048)
			(end 0.120396 0.2794)
			(stroke
				(width 0.1)
				(type default)
			)
			(layer "F.Fab")
		)
		(fp_line
			(start 0.120396 0.2794)
			(end -0.12065 0.2794)
			(stroke
				(width 0.1)
				(type default)
			)
			(layer "F.Fab")
		)
		(fp_line
			(start -0.12065 0.3048)
			(end -0.67945 0.3048)
			(stroke
				(width 0.1)
				(type default)
			)
			(layer "F.Fab")
		)
		(fp_line
			(start -0.12065 0.2794)
			(end -0.12065 0.3048)
			(stroke
				(width 0.1)
				(type default)
			)
			(layer "F.Fab")
		)
		(fp_line
			(start -0.12065 -0.2794)
			(end 0.12065 -0.2794)
			(stroke
				(width 0.1)
				(type default)
			)
			(layer "F.Fab")
		)
		(fp_line
			(start -0.12065 -0.305054)
			(end -0.12065 -0.2794)
			(stroke
				(width 0.1)
				(type default)
			)
			(layer "F.Fab")
		)
		(fp_line
			(start -0.67945 0.3048)
			(end -0.67945 -0.305054)
			(stroke
				(width 0.1)
				(type default)
			)
			(layer "F.Fab")
		)
		(fp_line
			(start -0.67945 -0.305054)
			(end -0.12065 -0.305054)
			(stroke
				(width 0.1)
				(type default)
			)
			(layer "F.Fab")
		)
		(pad "1" smd circle
			(at -0.40005 0 180)
			(size 0 0)
			(layers "F.Cu" "F.Mask" "F.Paste")
			(net "NCSI_NIC5_TXD1")
		)
		(pad "2" smd circle
			(at 0.40005 0 180)
			(size 0 0)
			(layers "F.Cu" "F.Mask" "F.Paste")
			(net "GND")
		)
	)
	(footprint ""
		(layer "F.Cu")
		(at 240.968276 -319.392554 180)
		(property "Reference" "PC243"
			(at 0 0 180)
			(layer "F.SilkS")
			(hide yes)
			(effects
				(font
					(size 1.27 1.27)
				)
			)
		)
		(property "Value" ""
			(at 0 0 180)
			(layer "F.Fab")
			(effects
				(font
					(size 1.27 1.27)
				)
			)
		)
		(duplicate_pad_numbers_are_jumpers no)
		(fp_line
			(start 0.7874 0.4064)
			(end -0.7874 0.4064)
			(stroke
				(width 0.1524)
				(type default)
			)
			(layer "F.SilkS")
		)
		(fp_line
			(start 0.7874 -0.4064)
			(end 0.7874 0.4064)
			(stroke
				(width 0.1524)
				(type default)
			)
			(layer "F.SilkS")
		)
		(fp_line
			(start -0.7874 0.4064)
			(end -0.7874 -0.4064)
			(stroke
				(width 0.1524)
				(type default)
			)
			(layer "F.SilkS")
		)
		(fp_line
			(start -0.7874 -0.4064)
			(end 0.7874 -0.4064)
			(stroke
				(width 0.1524)
				(type default)
			)
			(layer "F.SilkS")
		)
		(fp_line
			(start 0.67945 0.3048)
			(end 0.120396 0.3048)
			(stroke
				(width 0.1)
				(type default)
			)
			(layer "F.Fab")
		)
		(fp_line
			(start 0.67945 -0.3048)
			(end 0.67945 0.3048)
			(stroke
				(width 0.1)
				(type default)
			)
			(layer "F.Fab")
		)
		(fp_line
			(start 0.12065 -0.2794)
			(end 0.12065 -0.3048)
			(stroke
				(width 0.1)
				(type default)
			)
			(layer "F.Fab")
		)
		(fp_line
			(start 0.12065 -0.3048)
			(end 0.67945 -0.3048)
			(stroke
				(width 0.1)
				(type default)
			)
			(layer "F.Fab")
		)
		(fp_line
			(start 0.120396 0.3048)
			(end 0.120396 0.2794)
			(stroke
				(width 0.1)
				(type default)
			)
			(layer "F.Fab")
		)
		(fp_line
			(start 0.120396 0.2794)
			(end -0.12065 0.2794)
			(stroke
				(width 0.1)
				(type default)
			)
			(layer "F.Fab")
		)
		(fp_line
			(start -0.12065 0.3048)
			(end -0.67945 0.3048)
			(stroke
				(width 0.1)
				(type default)
			)
			(layer "F.Fab")
		)
		(fp_line
			(start -0.12065 0.2794)
			(end -0.12065 0.3048)
			(stroke
				(width 0.1)
				(type default)
			)
			(layer "F.Fab")
		)
		(fp_line
			(start -0.12065 -0.2794)
			(end 0.12065 -0.2794)
			(stroke
				(width 0.1)
				(type default)
			)
			(layer "F.Fab")
		)
		(fp_line
			(start -0.12065 -0.305054)
			(end -0.12065 -0.2794)
			(stroke
				(width 0.1)
				(type default)
			)
			(layer "F.Fab")
		)
		(fp_line
			(start -0.67945 0.3048)
			(end -0.67945 -0.305054)
			(stroke
				(width 0.1)
				(type default)
			)
			(layer "F.Fab")
		)
		(fp_line
			(start -0.67945 -0.305054)
			(end -0.12065 -0.305054)
			(stroke
				(width 0.1)
				(type default)
			)
			(layer "F.Fab")
		)
		(pad "1" smd circle
			(at -0.40005 0 180)
			(size 0 0)
			(layers "F.Cu" "F.Mask" "F.Paste")
			(net "P12V_AUX")
		)
		(pad "2" smd circle
			(at 0.40005 0 180)
			(size 0 0)
			(layers "F.Cu" "F.Mask" "F.Paste")
			(net "GND")
		)
	)
	(footprint ""
		(layer "F.Cu")
		(at 255.824736 -259.378958)
		(property "Reference" "R1397"
			(at 0 0 0)
			(layer "F.SilkS")
			(hide yes)
			(effects
				(font
					(size 1.27 1.27)
				)
			)
		)
		(property "Value" ""
			(at 0 0 0)
			(layer "F.Fab")
			(effects
				(font
					(size 1.27 1.27)
				)
			)
		)
		(duplicate_pad_numbers_are_jumpers no)
		(fp_line
			(start -0.7874 -0.4064)
			(end 0.7874 -0.4064)
			(stroke
				(width 0.1524)
				(type default)
			)
			(layer "F.SilkS")
		)
		(fp_line
			(start -0.7874 0.4064)
			(end -0.7874 -0.4064)
			(stroke
				(width 0.1524)
				(type default)
			)
			(layer "F.SilkS")
		)
		(fp_line
			(start 0.7874 -0.4064)
			(end 0.7874 0.4064)
			(stroke
				(width 0.1524)
				(type default)
			)
			(layer "F.SilkS")
		)
		(fp_line
			(start 0.7874 0.4064)
			(end -0.7874 0.4064)
			(stroke
				(width 0.1524)
				(type default)
			)
			(layer "F.SilkS")
		)
		(fp_line
			(start -0.67945 -0.305054)
			(end -0.12065 -0.305054)
			(stroke
				(width 0.1)
				(type default)
			)
			(layer "F.Fab")
		)
		(fp_line
			(start -0.67945 0.3048)
			(end -0.67945 -0.305054)
			(stroke
				(width 0.1)
				(type default)
			)
			(layer "F.Fab")
		)
		(fp_line
			(start -0.12065 -0.305054)
			(end -0.12065 -0.2794)
			(stroke
				(width 0.1)
				(type default)
			)
			(layer "F.Fab")
		)
		(fp_line
			(start -0.12065 -0.2794)
			(end 0.12065 -0.2794)
			(stroke
				(width 0.1)
				(type default)
			)
			(layer "F.Fab")
		)
		(fp_line
			(start -0.12065 0.2794)
			(end -0.12065 0.3048)
			(stroke
				(width 0.1)
				(type default)
			)
			(layer "F.Fab")
		)
		(fp_line
			(start -0.12065 0.3048)
			(end -0.67945 0.3048)
			(stroke
				(width 0.1)
				(type default)
			)
			(layer "F.Fab")
		)
		(fp_line
			(start 0.120396 0.2794)
			(end -0.12065 0.2794)
			(stroke
				(width 0.1)
				(type default)
			)
			(layer "F.Fab")
		)
		(fp_line
			(start 0.120396 0.3048)
			(end 0.120396 0.2794)
			(stroke
				(width 0.1)
				(type default)
			)
			(layer "F.Fab")
		)
		(fp_line
			(start 0.12065 -0.3048)
			(end 0.67945 -0.3048)
			(stroke
				(width 0.1)
				(type default)
			)
			(layer "F.Fab")
		)
		(fp_line
			(start 0.12065 -0.2794)
			(end 0.12065 -0.3048)
			(stroke
				(width 0.1)
				(type default)
			)
			(layer "F.Fab")
		)
		(fp_line
			(start 0.67945 -0.3048)
			(end 0.67945 0.3048)
			(stroke
				(width 0.1)
				(type default)
			)
			(layer "F.Fab")
		)
		(fp_line
			(start 0.67945 0.3048)
			(end 0.120396 0.3048)
			(stroke
				(width 0.1)
				(type default)
			)
			(layer "F.Fab")
		)
		(pad "1" smd circle
			(at -0.40005 0)
			(size 0 0)
			(layers "F.Cu" "F.Mask" "F.Paste")
			(net "PEX2_SYS_ERR_N_G")
		)
		(pad "2" smd circle
			(at 0.40005 0)
			(size 0 0)
			(layers "F.Cu" "F.Mask" "F.Paste")
			(net "P3V3_AUX")
		)
	)
	(footprint ""
		(layer "F.Cu")
		(at 28.782518 -29.875734)
		(property "Reference" "PU82"
			(at -3.360674 -1.147826 90)
			(unlocked yes)
			(layer "F.SilkS")
			(effects
				(font
					(size 0.7874 0.5842)
					(thickness 0.1524)
				)
			)
		)
		(property "Value" ""
			(at 0 0 0)
			(layer "F.Fab")
			(effects
				(font
					(size 1.27 1.27)
				)
			)
		)
		(duplicate_pad_numbers_are_jumpers no)
		(fp_line
			(start -1.239774 -1.495298)
			(end 1.239774 -1.495298)
			(stroke
				(width 0.1524)
				(type default)
			)
			(layer "F.SilkS")
		)
		(fp_line
			(start -1.239774 1.495298)
			(end -1.239774 -1.495298)
			(stroke
				(width 0.1524)
				(type default)
			)
			(layer "F.SilkS")
		)
		(fp_line
			(start 1.239774 -1.495298)
			(end 1.239774 1.495298)
			(stroke
				(width 0.1524)
				(type default)
			)
			(layer "F.SilkS")
		)
		(fp_line
			(start 1.239774 1.495298)
			(end -1.239774 1.495298)
			(stroke
				(width 0.1524)
				(type default)
			)
			(layer "F.SilkS")
		)
		(fp_poly
			(pts
				(xy -2.181352 -1.59639) (xy -2.899664 -0.878078) (xy -1.822196 -0.518922)
			)
			(stroke
				(width 0)
				(type default)
			)
			(fill yes)
			(layer "F.SilkS")
		)
		(fp_line
			(start -0.8001 -1.050036)
			(end 0.8001 -1.050036)
			(stroke
				(width 0.1)
				(type default)
			)
			(layer "F.Fab")
		)
		(fp_line
			(start -0.8001 1.050036)
			(end -0.8001 -1.050036)
			(stroke
				(width 0.1)
				(type default)
			)
			(layer "F.Fab")
		)
		(fp_line
			(start 0.8001 -1.050036)
			(end 0.8001 1.050036)
			(stroke
				(width 0.1)
				(type default)
			)
			(layer "F.Fab")
		)
		(fp_line
			(start 0.8001 1.050036)
			(end -0.8001 1.050036)
			(stroke
				(width 0.1)
				(type default)
			)
			(layer "F.Fab")
		)
		(fp_poly
			(pts
				(xy -2.458974 -0.508) (xy -2.458974 0.508) (xy -1.442974 0)
			)
			(stroke
				(width 0)
				(type default)
			)
			(fill yes)
			(layer "F.Fab")
		)
		(pad "1_2" smd circle
			(at -0.374904 0 90)
			(size 0 0)
			(layers "F.Cu" "F.Mask" "F.Paste")
			(net "P3V3_AUX")
		)
		(pad "3" smd rect
			(at -0.499872 0.999998)
			(size 0.254 0.7112)
			(layers "F.Cu" "F.Mask" "F.Paste")
			(net "GND")
		)
		(pad "4" smd rect
			(at 0 0.999998)
			(size 0.254 0.7112)
			(layers "F.Cu" "F.Mask" "F.Paste")
			(net "P3V3_SSD1_CO_ILIMIT")
		)
		(pad "5" smd rect
			(at 0.499872 0.999998)
			(size 0.254 0.7112)
			(layers "F.Cu" "F.Mask" "F.Paste")
			(net "P3V3_SSD1_CO_MODE")
		)
		(pad "6_7" smd circle
			(at 0.374904 0 270)
			(size 0 0)
			(layers "F.Cu" "F.Mask" "F.Paste")
			(net "P3V3_SSD1")
		)
		(pad "8" smd rect
			(at 0.499872 -0.999998)
			(size 0.254 0.7112)
			(layers "F.Cu" "F.Mask" "F.Paste")
			(net "P3V3_SSD1_CO_GATE")
		)
		(pad "9" smd rect
			(at 0 -0.999998)
			(size 0.254 0.7112)
			(layers "F.Cu" "F.Mask" "F.Paste")
			(net "P3V3_SSD1_CO_EN")
		)
		(pad "10" smd rect
			(at -0.499872 -0.999998)
			(size 0.254 0.7112)
			(layers "F.Cu" "F.Mask" "F.Paste")
			(net "P3V3_SSD1_CO_DV_DT")
		)
	)
	(footprint ""
		(layer "F.Cu")
		(at 16.431768 -162.003994 -90)
		(property "Reference" "R903"
			(at 0 0 270)
			(layer "F.SilkS")
			(hide yes)
			(effects
				(font
					(size 1.27 1.27)
				)
			)
		)
		(property "Value" ""
			(at 0 0 270)
			(layer "F.Fab")
			(effects
				(font
					(size 1.27 1.27)
				)
			)
		)
		(duplicate_pad_numbers_are_jumpers no)
		(fp_line
			(start -0.7874 0.4064)
			(end -0.7874 -0.4064)
			(stroke
				(width 0.1524)
				(type default)
			)
			(layer "F.SilkS")
		)
		(fp_line
			(start 0.7874 0.4064)
			(end -0.7874 0.4064)
			(stroke
				(width 0.1524)
				(type default)
			)
			(layer "F.SilkS")
		)
		(fp_line
			(start -0.7874 -0.4064)
			(end 0.7874 -0.4064)
			(stroke
				(width 0.1524)
				(type default)
			)
			(layer "F.SilkS")
		)
		(fp_line
			(start 0.7874 -0.4064)
			(end 0.7874 0.4064)
			(stroke
				(width 0.1524)
				(type default)
			)
			(layer "F.SilkS")
		)
		(fp_line
			(start -0.67945 0.3048)
			(end -0.67945 -0.305054)
			(stroke
				(width 0.1)
				(type default)
			)
			(layer "F.Fab")
		)
		(fp_line
			(start -0.12065 0.3048)
			(end -0.67945 0.3048)
			(stroke
				(width 0.1)
				(type default)
			)
			(layer "F.Fab")
		)
		(fp_line
			(start 0.120396 0.3048)
			(end 0.120396 0.2794)
			(stroke
				(width 0.1)
				(type default)
			)
			(layer "F.Fab")
		)
		(fp_line
			(start 0.67945 0.3048)
			(end 0.120396 0.3048)
			(stroke
				(width 0.1)
				(type default)
			)
			(layer "F.Fab")
		)
		(fp_line
			(start -0.12065 0.2794)
			(end -0.12065 0.3048)
			(stroke
				(width 0.1)
				(type default)
			)
			(layer "F.Fab")
		)
		(fp_line
			(start 0.120396 0.2794)
			(end -0.12065 0.2794)
			(stroke
				(width 0.1)
				(type default)
			)
			(layer "F.Fab")
		)
		(fp_line
			(start -0.12065 -0.2794)
			(end 0.12065 -0.2794)
			(stroke
				(width 0.1)
				(type default)
			)
			(layer "F.Fab")
		)
		(fp_line
			(start 0.12065 -0.2794)
			(end 0.12065 -0.3048)
			(stroke
				(width 0.1)
				(type default)
			)
			(layer "F.Fab")
		)
		(fp_line
			(start 0.12065 -0.3048)
			(end 0.67945 -0.3048)
			(stroke
				(width 0.1)
				(type default)
			)
			(layer "F.Fab")
		)
		(fp_line
			(start 0.67945 -0.3048)
			(end 0.67945 0.3048)
			(stroke
				(width 0.1)
				(type default)
			)
			(layer "F.Fab")
		)
		(fp_line
			(start -0.67945 -0.305054)
			(end -0.12065 -0.305054)
			(stroke
				(width 0.1)
				(type default)
			)
			(layer "F.Fab")
		)
		(fp_line
			(start -0.12065 -0.305054)
			(end -0.12065 -0.2794)
			(stroke
				(width 0.1)
				(type default)
			)
			(layer "F.Fab")
		)
		(pad "1" smd circle
			(at -0.40005 0 270)
			(size 0 0)
			(layers "F.Cu" "F.Mask" "F.Paste")
			(net "HP_NIC0_EN")
		)
		(pad "2" smd circle
			(at 0.40005 0 270)
			(size 0 0)
			(layers "F.Cu" "F.Mask" "F.Paste")
			(net "P12V_NIC0_CO_EN")
		)
	)
	(footprint ""
		(layer "F.Cu")
		(at 336.042 -148.971 180)
		(property "Reference" "R4827"
			(at 0 0 180)
			(layer "F.SilkS")
			(hide yes)
			(effects
				(font
					(size 1.27 1.27)
				)
			)
		)
		(property "Value" ""
			(at 0 0 180)
			(layer "F.Fab")
			(effects
				(font
					(size 1.27 1.27)
				)
			)
		)
		(duplicate_pad_numbers_are_jumpers no)
		(fp_line
			(start 0.7874 0.4064)
			(end -0.7874 0.4064)
			(stroke
				(width 0.1524)
				(type default)
			)
			(layer "F.SilkS")
		)
		(fp_line
			(start 0.7874 -0.4064)
			(end 0.7874 0.4064)
			(stroke
				(width 0.1524)
				(type default)
			)
			(layer "F.SilkS")
		)
		(fp_line
			(start -0.7874 0.4064)
			(end -0.7874 -0.4064)
			(stroke
				(width 0.1524)
				(type default)
			)
			(layer "F.SilkS")
		)
		(fp_line
			(start -0.7874 -0.4064)
			(end 0.7874 -0.4064)
			(stroke
				(width 0.1524)
				(type default)
			)
			(layer "F.SilkS")
		)
		(fp_line
			(start 0.67945 0.3048)
			(end 0.120396 0.3048)
			(stroke
				(width 0.1)
				(type default)
			)
			(layer "F.Fab")
		)
		(fp_line
			(start 0.67945 -0.3048)
			(end 0.67945 0.3048)
			(stroke
				(width 0.1)
				(type default)
			)
			(layer "F.Fab")
		)
		(fp_line
			(start 0.12065 -0.2794)
			(end 0.12065 -0.3048)
			(stroke
				(width 0.1)
				(type default)
			)
			(layer "F.Fab")
		)
		(fp_line
			(start 0.12065 -0.3048)
			(end 0.67945 -0.3048)
			(stroke
				(width 0.1)
				(type default)
			)
			(layer "F.Fab")
		)
		(fp_line
			(start 0.120396 0.3048)
			(end 0.120396 0.2794)
			(stroke
				(width 0.1)
				(type default)
			)
			(layer "F.Fab")
		)
		(fp_line
			(start 0.120396 0.2794)
			(end -0.12065 0.2794)
			(stroke
				(width 0.1)
				(type default)
			)
			(layer "F.Fab")
		)
		(fp_line
			(start -0.12065 0.3048)
			(end -0.67945 0.3048)
			(stroke
				(width 0.1)
				(type default)
			)
			(layer "F.Fab")
		)
		(fp_line
			(start -0.12065 0.2794)
			(end -0.12065 0.3048)
			(stroke
				(width 0.1)
				(type default)
			)
			(layer "F.Fab")
		)
		(fp_line
			(start -0.12065 -0.2794)
			(end 0.12065 -0.2794)
			(stroke
				(width 0.1)
				(type default)
			)
			(layer "F.Fab")
		)
		(fp_line
			(start -0.12065 -0.305054)
			(end -0.12065 -0.2794)
			(stroke
				(width 0.1)
				(type default)
			)
			(layer "F.Fab")
		)
		(fp_line
			(start -0.67945 0.3048)
			(end -0.67945 -0.305054)
			(stroke
				(width 0.1)
				(type default)
			)
			(layer "F.Fab")
		)
		(fp_line
			(start -0.67945 -0.305054)
			(end -0.12065 -0.305054)
			(stroke
				(width 0.1)
				(type default)
			)
			(layer "F.Fab")
		)
		(pad "1" smd circle
			(at -0.40005 0 180)
			(size 0 0)
			(layers "F.Cu" "F.Mask" "F.Paste")
			(net "PCA9555_1_PEX3_A2")
		)
		(pad "2" smd circle
			(at 0.40005 0 180)
			(size 0 0)
			(layers "F.Cu" "F.Mask" "F.Paste")
			(net "P3V3_AUX")
		)
	)
)
